# S9S_MB_2U (Grand Teton) — schematic netlist excerpt (pin names and nets, part order shuffled) for the footprints in the layout excerpt that follows; sources: Cadence DE-HDL packaged netlist, KiCad conversion of 03242023_DA0F0TMBIJ0_F0T_Motherboard_J_brd_V01_OCP.brd

C423  Q_CAP  22UF 4V 20% X6S  pkg C0402  page 77 : A = PVCCD_HV_CPU1 ; B = GND
R1720  Q_RES  0 5% EMPTY  pkg 0402LF  page 179 : A = XTAL_PCH_25M_IN_R ; B = XTAL_PCH_25M_IN

(kicad_pcb
	(version 20260206)
	(generator "pcbnew")
	(generator_version "10.0")
	(general
		(thickness 1.6)
		(legacy_teardrops no)
	)
	(paper "A4")
	(title_block
		(title "03242023_DA0F0TMBIJ0_F0T_Motherboard_J_brd_V01_OCP.brd")
		(comment 1 "Grand Teton / footprints 2169-2171 of 6105")
	)
	(layers
		(0 "F.Cu" signal "TOP")
		(4 "In1.Cu" signal "GND")
		(6 "In2.Cu" signal "IN1")
		(8 "In3.Cu" signal "GND1")
		(10 "In4.Cu" signal "IN2")
		(12 "In5.Cu" signal "GND2")
		(14 "In6.Cu" signal "IN3")
		(16 "In7.Cu" signal "GND3")
		(18 "In8.Cu" signal "VCC")
		(20 "In9.Cu" signal "VCC1")
		(22 "In10.Cu" signal "GND4")
		(24 "In11.Cu" signal "IN4")
		(26 "In12.Cu" signal "GND5")
		(28 "In13.Cu" signal "IN5")
		(30 "In14.Cu" signal "GND6")
		(32 "In15.Cu" signal "IN6")
		(34 "In16.Cu" signal "GND7")
		(2 "B.Cu" signal "BOTTOM")
		(9 "F.Adhes" user "F.Adhesive")
		(11 "B.Adhes" user "B.Adhesive")
		(13 "F.Paste" user "Package Geometry/Pastemask Top")
		(15 "B.Paste" user "Package Geometry/Pastemask Bottom")
		(5 "F.SilkS" user "Ref Des/Silkscreen Top")
		(7 "B.SilkS" user "Ref Des/Silkscreen Bottom")
		(1 "F.Mask" user "Board Geometry/Soldermask Top")
		(3 "B.Mask" user "Board Geometry/Soldermask Bottom")
		(17 "Dwgs.User" user "User.Drawings")
		(19 "Cmts.User" user "User.Comments")
		(21 "Eco1.User" user "User.Eco1")
		(23 "Eco2.User" user "User.Eco2")
		(25 "Edge.Cuts" user "Board Geometry/Outline")
		(27 "Margin" user)
		(31 "F.CrtYd" user "Package Geometry/Place Bound Top")
		(29 "B.CrtYd" user "Package Geometry/Place Bound Bottom")
		(35 "F.Fab" user "Ref Des/Assembly Top")
		(33 "B.Fab" user "Ref Des/Assembly Bottom")
	)
	(footprint ""
		(layer "F.Cu")
		(at 104.349804 -245.634256 -90)
		(property "Reference" "C423"
			(at 0 0 270)
			(layer "F.SilkS")
			(hide yes)
			(effects
				(font
					(size 1.27 1.27)
				)
			)
		)
		(property "Value" ""
			(at 0 0 270)
			(layer "F.Fab")
			(effects
				(font
					(size 1.27 1.27)
				)
			)
		)
		(duplicate_pad_numbers_are_jumpers no)
		(fp_line
			(start -0.7874 0.4064)
			(end -0.7874 -0.4064)
			(stroke
				(width 0.1524)
				(type default)
			)
			(layer "F.SilkS")
		)
		(fp_line
			(start 0.7874 0.4064)
			(end -0.7874 0.4064)
			(stroke
				(width 0.1524)
				(type default)
			)
			(layer "F.SilkS")
		)
		(fp_line
			(start -0.7874 -0.4064)
			(end 0.7874 -0.4064)
			(stroke
				(width 0.1524)
				(type default)
			)
			(layer "F.SilkS")
		)
		(fp_line
			(start 0.7874 -0.4064)
			(end 0.7874 0.4064)
			(stroke
				(width 0.1524)
				(type default)
			)
			(layer "F.SilkS")
		)
		(fp_line
			(start -0.67945 0.3048)
			(end -0.67945 -0.305054)
			(stroke
				(width 0.1)
				(type default)
			)
			(layer "F.Fab")
		)
		(fp_line
			(start -0.12065 0.3048)
			(end -0.67945 0.3048)
			(stroke
				(width 0.1)
				(type default)
			)
			(layer "F.Fab")
		)
		(fp_line
			(start 0.120396 0.3048)
			(end 0.120396 0.2794)
			(stroke
				(width 0.1)
				(type default)
			)
			(layer "F.Fab")
		)
		(fp_line
			(start 0.67945 0.3048)
			(end 0.120396 0.3048)
			(stroke
				(width 0.1)
				(type default)
			)
			(layer "F.Fab")
		)
		(fp_line
			(start -0.12065 0.2794)
			(end -0.12065 0.3048)
			(stroke
				(width 0.1)
				(type default)
			)
			(layer "F.Fab")
		)
		(fp_line
			(start 0.120396 0.2794)
			(end -0.12065 0.2794)
			(stroke
				(width 0.1)
				(type default)
			)
			(layer "F.Fab")
		)
		(fp_line
			(start -0.12065 -0.2794)
			(end 0.12065 -0.2794)
			(stroke
				(width 0.1)
				(type default)
			)
			(layer "F.Fab")
		)
		(fp_line
			(start 0.12065 -0.2794)
			(end 0.12065 -0.3048)
			(stroke
				(width 0.1)
				(type default)
			)
			(layer "F.Fab")
		)
		(fp_line
			(start 0.12065 -0.3048)
			(end 0.67945 -0.3048)
			(stroke
				(width 0.1)
				(type default)
			)
			(layer "F.Fab")
		)
		(fp_line
			(start 0.67945 -0.3048)
			(end 0.67945 0.3048)
			(stroke
				(width 0.1)
				(type default)
			)
			(layer "F.Fab")
		)
		(fp_line
			(start -0.67945 -0.305054)
			(end -0.12065 -0.305054)
			(stroke
				(width 0.1)
				(type default)
			)
			(layer "F.Fab")
		)
		(fp_line
			(start -0.12065 -0.305054)
			(end -0.12065 -0.2794)
			(stroke
				(width 0.1)
				(type default)
			)
			(layer "F.Fab")
		)
		(pad "1" smd circle
			(at -0.40005 0 270)
			(size 0 0)
			(layers "F.Cu" "F.Mask" "F.Paste")
			(net "PVCCD_HV_CPU1")
		)
		(pad "2" smd circle
			(at 0.40005 0 270)
			(size 0 0)
			(layers "F.Cu" "F.Mask" "F.Paste")
			(net "GND")
		)
	)
	(footprint ""
		(layer "F.Cu")
		(at 336.319622 -63.363348 -90)
		(property "Reference" "R1720"
			(at 0 0 270)
			(layer "F.SilkS")
			(hide yes)
			(effects
				(font
					(size 1.27 1.27)
				)
			)
		)
		(property "Value" ""
			(at 0 0 270)
			(layer "F.Fab")
			(effects
				(font
					(size 1.27 1.27)
				)
			)
		)
		(duplicate_pad_numbers_are_jumpers no)
		(fp_line
			(start -0.7874 0.4064)
			(end -0.7874 -0.4064)
			(stroke
				(width 0.1524)
				(type default)
			)
			(layer "F.SilkS")
		)
		(fp_line
			(start 0.7874 0.4064)
			(end -0.7874 0.4064)
			(stroke
				(width 0.1524)
				(type default)
			)
			(layer "F.SilkS")
		)
		(fp_line
			(start -0.7874 -0.4064)
			(end 0.7874 -0.4064)
			(stroke
				(width 0.1524)
				(type default)
			)
			(layer "F.SilkS")
		)
		(fp_line
			(start 0.7874 -0.4064)
			(end 0.7874 0.4064)
			(stroke
				(width 0.1524)
				(type default)
			)
			(layer "F.SilkS")
		)
		(fp_line
			(start -0.67945 0.3048)
			(end -0.67945 -0.305054)
			(stroke
				(width 0.1)
				(type default)
			)
			(layer "F.Fab")
		)
		(fp_line
			(start -0.12065 0.3048)
			(end -0.67945 0.3048)
			(stroke
				(width 0.1)
				(type default)
			)
			(layer "F.Fab")
		)
		(fp_line
			(start 0.120396 0.3048)
			(end 0.120396 0.2794)
			(stroke
				(width 0.1)
				(type default)
			)
			(layer "F.Fab")
		)
		(fp_line
			(start 0.67945 0.3048)
			(end 0.120396 0.3048)
			(stroke
				(width 0.1)
				(type default)
			)
			(layer "F.Fab")
		)
		(fp_line
			(start -0.12065 0.2794)
			(end -0.12065 0.3048)
			(stroke
				(width 0.1)
				(type default)
			)
			(layer "F.Fab")
		)
		(fp_line
			(start 0.120396 0.2794)
			(end -0.12065 0.2794)
			(stroke
				(width 0.1)
				(type default)
			)
			(layer "F.Fab")
		)
		(fp_line
			(start -0.12065 -0.2794)
			(end 0.12065 -0.2794)
			(stroke
				(width 0.1)
				(type default)
			)
			(layer "F.Fab")
		)
		(fp_line
			(start 0.12065 -0.2794)
			(end 0.12065 -0.3048)
			(stroke
				(width 0.1)
				(type default)
			)
			(layer "F.Fab")
		)
		(fp_line
			(start 0.12065 -0.3048)
			(end 0.67945 -0.3048)
			(stroke
				(width 0.1)
				(type default)
			)
			(layer "F.Fab")
		)
		(fp_line
			(start 0.67945 -0.3048)
			(end 0.67945 0.3048)
			(stroke
				(width 0.1)
				(type default)
			)
			(layer "F.Fab")
		)
		(fp_line
			(start -0.67945 -0.305054)
			(end -0.12065 -0.305054)
			(stroke
				(width 0.1)
				(type default)
			)
			(layer "F.Fab")
		)
		(fp_line
			(start -0.12065 -0.305054)
			(end -0.12065 -0.2794)
			(stroke
				(width 0.1)
				(type default)
			)
			(layer "F.Fab")
		)
		(pad "1" smd circle
			(at -0.40005 0 270)
			(size 0 0)
			(layers "F.Cu" "F.Mask" "F.Paste")
			(net "XTAL_PCH_25M_IN_R")
		)
		(pad "2" smd circle
			(at 0.40005 0 270)
			(size 0 0)
			(layers "F.Cu" "F.Mask" "F.Paste")
			(net "XTAL_PCH_25M_IN")
		)
	)
	(footprint ""
		(layer "F.Cu")
		(at 125.26772 -164.447728)
		(property "Reference" ""
			(at 0 0 0)
			(layer "F.SilkS")
			(hide yes)
			(effects
				(font
					(size 1.27 1.27)
				)
			)
		)
		(property "Value" ""
			(at 0 0 0)
			(layer "F.Fab")
			(effects
				(font
					(size 1.27 1.27)
				)
			)
		)
		(duplicate_pad_numbers_are_jumpers no)
		(pad "1" smd circle
			(at 0 0)
			(size 0.9906 0.9906)
			(layers "F.Cu" "F.Mask" "F.Paste")
			(net "Net_290")
		)
		(zone
			(layer "F.Cu")
			(hatch none 0.5)
			(connect_pads
				(clearance 0)
			)
			(min_thickness 0.25)
			(keepout
				(tracks not_allowed)
				(vias allowed)
				(pads allowed)
				(copperpour not_allowed)
				(footprints allowed)
			)
			(placement
				(enabled no)
				(sheetname "")
			)
			(fill
				(thermal_gap 0.5)
				(thermal_bridge_width 0.5)
				(island_removal_mode 0)
			)
			(polygon
				(pts
					(arc
						(start 126.89332 -164.447728)
						(mid 123.64212 -164.447728)
						(end 126.89332 -164.447728)
					)
				)
			)
		)
	)
)
